(kicad_pcb
	(version 20260206)
	(generator "pcbnew")
	(generator_version "10.0")
	(general
		(thickness 1.6)
		(legacy_teardrops no)
	)
	(paper "A4")
	(title_block
		(title "Wiwynn_Tioga_Pass_MB.brd")
		(comment 1 "Tioga Pass / footprint 153 of 4770 (U25W4), pads 107-211 of 456")
	)
	(layers
		(0 "F.Cu" signal "TOP")
		(4 "In1.Cu" signal "L2GND")
		(6 "In2.Cu" signal "L3")
		(8 "In3.Cu" signal "L4GND")
		(10 "In4.Cu" signal "L5")
		(12 "In5.Cu" signal "L6GND")
		(14 "In6.Cu" signal "L7VCC")
		(16 "In7.Cu" signal "L8VCC")
		(18 "In8.Cu" signal "L9GND")
		(20 "In9.Cu" signal "L10")
		(22 "In10.Cu" signal "L11GND")
		(24 "In11.Cu" signal "L12")
		(26 "In12.Cu" signal "L13GND")
		(2 "B.Cu" signal "BOTTOM")
		(9 "F.Adhes" user "F.Adhesive")
		(11 "B.Adhes" user "B.Adhesive")
		(13 "F.Paste" user "Package Geometry/Pastemask Top")
		(15 "B.Paste" user "Package Geometry/Pastemask Bottom")
		(5 "F.SilkS" user "Ref Des/Silkscreen Top")
		(7 "B.SilkS" user "Ref Des/Silkscreen Bottom")
		(1 "F.Mask" user "Board Geometry/Soldermask Top")
		(3 "B.Mask" user "Board Geometry/Soldermask Bottom")
		(17 "Dwgs.User" user "User.Drawings")
		(19 "Cmts.User" user "User.Comments")
		(21 "Eco1.User" user "User.Eco1")
		(23 "Eco2.User" user "User.Eco2")
		(25 "Edge.Cuts" user "Board Geometry/Outline")
		(27 "Margin" user)
		(31 "F.CrtYd" user "Package Geometry/Place Bound Top")
		(29 "B.CrtYd" user "Package Geometry/Place Bound Bottom")
		(35 "F.Fab" user "Ref Des/Assembly Top")
		(33 "B.Fab" user "Ref Des/Assembly Bottom")
	)
	(footprint ""
		(layer "F.Cu")
		(at 415.490152 -34.934652 90)
		(property "Reference" "U25W4"
			(at 0 0 90)
			(layer "F.SilkS")
			(hide yes)
			(effects
				(font
					(size 1.27 1.27)
				)
			)
		)
		(property "Value" "*"
			(at -17.0307 -8.698992 90)
			(unlocked yes)
			(layer "F.Fab")
			(hide yes)
			(effects
				(font
					(size 1.27 1.016)
					(thickness 0.1524)
				)
			)
		)
		(property "Device Type" "AST2520A1-GP-GP_ASIC2-GB1-AST2A"
			(at -17.0307 -10.222992 90)
			(unlocked yes)
			(layer "F.Fab")
			(hide yes)
			(effects
				(font
					(size 1.27 1.016)
					(thickness 0.1524)
				)
			)
		)
		(duplicate_pad_numbers_are_jumpers no)
		(pad "C19" smd circle
			(at 5.999988 -6.800088 90)
			(size 0.3556 0.3556)
			(layers "F.Cu" "F.Mask" "F.Paste")
			(net "FM_PCH_BMC_THERMTRIP_N")
		)
		(pad "C20" smd circle
			(at 6.800088 -6.800088 90)
			(size 0.4064 0.4064)
			(layers "F.Cu" "F.Mask" "F.Paste")
			(net "RST_BMC_SYSRST_BTN_OUT_N")
		)
		(pad "C21" smd circle
			(at 7.599934 -6.800088 90)
			(size 0.4064 0.4064)
			(layers "F.Cu" "F.Mask" "F.Paste")
			(net "FM_CPU_ERR1_LVT3_BMC_N")
		)
		(pad "C22" smd circle
			(at 8.400034 -6.800088 90)
			(size 0.4064 0.4064)
			(layers "F.Cu" "F.Mask" "F.Paste")
			(net "CLK_24M_BMC_LPC")
		)
		(pad "D1" smd circle
			(at -8.400034 -5.999988 90)
			(size 0.3556 0.3556)
			(layers "F.Cu" "F.Mask" "F.Paste")
			(net "RMII_SPRNGVLLE_BMC_PCH_RXD1")
		)
		(pad "D2" smd circle
			(at -7.599934 -5.999988 90)
			(size 0.3556 0.3556)
			(layers "F.Cu" "F.Mask" "F.Paste")
			(net "RMII_BMC_PCH_SPRNGVLLE_CRSDV")
		)
		(pad "D3" smd circle
			(at -6.800088 -5.999988 90)
			(size 0.3556 0.3556)
			(layers "F.Cu" "F.Mask" "F.Paste")
			(net "Net_308")
		)
		(pad "D4" smd circle
			(at -5.999988 -5.999988 90)
			(size 0.3556 0.3556)
			(layers "F.Cu" "F.Mask" "F.Paste")
			(net "TP_RGMII2TXD3_GPIOU3")
		)
		(pad "D5" smd circle
			(at -5.199888 -5.999988 90)
			(size 0.3556 0.3556)
			(layers "F.Cu" "F.Mask" "F.Paste")
			(net "TP_RGMII2TXD2_GPIOU2")
		)
		(pad "D6" smd circle
			(at -4.400042 -5.999988 90)
			(size 0.3556 0.3556)
			(layers "F.Cu" "F.Mask" "F.Paste")
			(net "RMII_BMC_OCP_RXD1")
		)
		(pad "D7" smd circle
			(at -3.599942 -5.999988 90)
			(size 0.3556 0.3556)
			(layers "F.Cu" "F.Mask" "F.Paste")
			(net "TP_RGMII1TXD3_GPIOT5")
		)
		(pad "D8" smd circle
			(at -2.800096 -5.999988 90)
			(size 0.3556 0.3556)
			(layers "F.Cu" "F.Mask" "F.Paste")
			(net "FM_SLT_CFG0")
		)
		(pad "D9" smd circle
			(at -1.999996 -5.999988 90)
			(size 0.3556 0.3556)
			(layers "F.Cu" "F.Mask" "F.Paste")
			(net "SMB_PEHPCPU0_STBY_LVC3_SDA")
		)
		(pad "D10" smd circle
			(at -1.199896 -5.999988 90)
			(size 0.3556 0.3556)
			(layers "F.Cu" "F.Mask" "F.Paste")
			(net "SMB_PEHPCPU1_STBY_LVC3_SCL")
		)
		(pad "D11" smd circle
			(at -0.40005 -5.999988 90)
			(size 0.3556 0.3556)
			(layers "F.Cu" "F.Mask" "F.Paste")
			(net "JTAG_BMC_TDO")
		)
		(pad "D12" smd circle
			(at 0.40005 -5.999988 90)
			(size 0.3556 0.3556)
			(layers "F.Cu" "F.Mask" "F.Paste")
			(net "JTAG_BMC_TDI")
		)
		(pad "D13" smd circle
			(at 1.199896 -5.999988 90)
			(size 0.3556 0.3556)
			(layers "F.Cu" "F.Mask" "F.Paste")
			(net "TP_BMC_GPIOA2")
		)
		(pad "D14" smd circle
			(at 1.999996 -5.999988 90)
			(size 0.3556 0.3556)
			(layers "F.Cu" "F.Mask" "F.Paste")
			(net "FM_CPLD_BMC_PWRDN_N")
		)
		(pad "D15" smd circle
			(at 2.800096 -5.999988 90)
			(size 0.3556 0.3556)
			(layers "F.Cu" "F.Mask" "F.Paste")
			(net "IRQ_MEZZ_LAN_ALERT_N")
		)
		(pad "D16" smd circle
			(at 3.599942 -5.999988 90)
			(size 0.3556 0.3556)
			(layers "F.Cu" "F.Mask" "F.Paste")
			(net "IRQ_OOB_MGMT_RISER_ALERT_N")
		)
		(pad "D17" smd circle
			(at 4.400042 -5.999988 90)
			(size 0.3556 0.3556)
			(layers "F.Cu" "F.Mask" "F.Paste")
			(net "LED_POSTCODE_2")
		)
		(pad "D18" smd circle
			(at 5.199888 -5.999988 90)
			(size 0.3556 0.3556)
			(layers "F.Cu" "F.Mask" "F.Paste")
			(net "LED_POSTCODE_7")
		)
		(pad "D19" smd circle
			(at 5.999988 -5.999988 90)
			(size 0.3556 0.3556)
			(layers "F.Cu" "F.Mask" "F.Paste")
			(net "IRQ_BMC_PCH_NMI_STBY_N")
		)
		(pad "D20" smd circle
			(at 6.800088 -5.999988 90)
			(size 0.3556 0.3556)
			(layers "F.Cu" "F.Mask" "F.Paste")
			(net "FM_BOARD_REV_ID1")
		)
		(pad "D21" smd circle
			(at 7.599934 -5.999988 90)
			(size 0.3556 0.3556)
			(layers "F.Cu" "F.Mask" "F.Paste")
			(net "IRQ_DIMM_SAVE_LVT3_N")
		)
		(pad "D22" smd circle
			(at 8.400034 -5.999988 90)
			(size 0.3556 0.3556)
			(layers "F.Cu" "F.Mask" "F.Paste")
			(net "LPC_LAD2_IO2_R")
		)
		(pad "E1" smd circle
			(at -8.400034 -5.199888 90)
			(size 0.3556 0.3556)
			(layers "F.Cu" "F.Mask" "F.Paste")
			(net "A_P1V05_STBY_PCH_SENSOR")
		)
		(pad "E2" smd circle
			(at -7.599934 -5.199888 90)
			(size 0.3556 0.3556)
			(layers "F.Cu" "F.Mask" "F.Paste")
			(net "A_P12V_STBY_SCALED")
		)
		(pad "E3" smd circle
			(at -6.800088 -5.199888 90)
			(size 0.3556 0.3556)
			(layers "F.Cu" "F.Mask" "F.Paste")
			(net "A_P3V3_STBY_SCALED")
		)
		(pad "E4" smd circle
			(at -5.999988 -5.199888 90)
			(size 0.3556 0.3556)
			(layers "F.Cu" "F.Mask" "F.Paste")
			(net "VCCBAT_TW12")
		)
		(pad "E5" smd circle
			(at -5.199888 -5.199888 90)
			(size 0.3556 0.3556)
			(layers "F.Cu" "F.Mask" "F.Paste")
			(net "GND")
		)
		(pad "E6" smd circle
			(at -4.400042 -5.199888 90)
			(size 0.3556 0.3556)
			(layers "F.Cu" "F.Mask" "F.Paste")
			(net "RMII_BMC_PCH_SPRNGVLLE_RXER")
		)
		(pad "E7" smd circle
			(at -3.599942 -5.199888 90)
			(size 0.3556 0.3556)
			(layers "F.Cu" "F.Mask" "F.Paste")
			(net "TP_RGMII1TXD2_GPIOT4")
		)
		(pad "E8" smd circle
			(at -2.800096 -5.199888 90)
			(size 0.3556 0.3556)
			(layers "F.Cu" "F.Mask" "F.Paste")
			(net "GND")
		)
		(pad "E9" smd circle
			(at -1.999996 -5.199888 90)
			(size 0.3556 0.3556)
			(layers "F.Cu" "F.Mask" "F.Paste")
			(net "RMII_BMC_OCP_TXEN_R")
		)
		(pad "E10" smd circle
			(at -1.199896 -5.199888 90)
			(size 0.3556 0.3556)
			(layers "F.Cu" "F.Mask" "F.Paste")
			(net "FM_SLT_CFG1")
		)
		(pad "E11" smd circle
			(at -0.40005 -5.199888 90)
			(size 0.3556 0.3556)
			(layers "F.Cu" "F.Mask" "F.Paste")
			(net "JTAG_BMC_TRST_N")
		)
		(pad "E12" smd circle
			(at 0.40005 -5.199888 90)
			(size 0.3556 0.3556)
			(layers "F.Cu" "F.Mask" "F.Paste")
			(net "SMB_PEHPCPU1_STBY_LVC3_SDA")
		)
		(pad "E13" smd circle
			(at 1.199896 -5.199888 90)
			(size 0.3556 0.3556)
			(layers "F.Cu" "F.Mask" "F.Paste")
			(net "FM_BMC_SYS_THROTTLE_R_N")
		)
		(pad "E14" smd circle
			(at 1.999996 -5.199888 90)
			(size 0.3556 0.3556)
			(layers "F.Cu" "F.Mask" "F.Paste")
			(net "FM_BIOS_SMI_ACTIVE_N")
		)
		(pad "E15" smd circle
			(at 2.800096 -5.199888 90)
			(size 0.3556 0.3556)
			(layers "F.Cu" "F.Mask" "F.Paste")
			(net "FM_CPU1_FIVR_FAULT_LVT3_R_N")
		)
		(pad "E16" smd circle
			(at 3.599942 -5.199888 90)
			(size 0.3556 0.3556)
			(layers "F.Cu" "F.Mask" "F.Paste")
			(net "FM_CPU0_SKTOCC_LVT3_N")
		)
		(pad "E17" smd circle
			(at 4.400042 -5.199888 90)
			(size 0.3556 0.3556)
			(layers "F.Cu" "F.Mask" "F.Paste")
			(net "IRQ_PCH_NIC_ALERT_N")
		)
		(pad "E18" smd circle
			(at 5.199888 -5.199888 90)
			(size 0.3556 0.3556)
			(layers "F.Cu" "F.Mask" "F.Paste")
			(net "FP_NMI_BTN_N")
		)
		(pad "E19" smd circle
			(at 5.999988 -5.199888 90)
			(size 0.3556 0.3556)
			(layers "F.Cu" "F.Mask" "F.Paste")
			(net "FM_CPU_CATERR_LVT3_N")
		)
		(pad "E20" smd circle
			(at 6.800088 -5.199888 90)
			(size 0.3556 0.3556)
			(layers "F.Cu" "F.Mask" "F.Paste")
			(net "FM_BOARD_REV_ID2")
		)
		(pad "E21" smd circle
			(at 7.599934 -5.199888 90)
			(size 0.3556 0.3556)
			(layers "F.Cu" "F.Mask" "F.Paste")
			(net "FM_BOARD_REV_ID0")
		)
		(pad "E22" smd circle
			(at 8.400034 -5.199888 90)
			(size 0.3556 0.3556)
			(layers "F.Cu" "F.Mask" "F.Paste")
			(net "LPC_LAD3_IO3_R")
		)
		(pad "F1" smd circle
			(at -8.400034 -4.400042 90)
			(size 0.3556 0.3556)
			(layers "F.Cu" "F.Mask" "F.Paste")
			(net "FM_GLOBAL_RST_WARN_N_R")
		)
		(pad "F2" smd circle
			(at -7.599934 -4.400042 90)
			(size 0.3556 0.3556)
			(layers "F.Cu" "F.Mask" "F.Paste")
			(net "GND")
		)
		(pad "F3" smd circle
			(at -6.800088 -4.400042 90)
			(size 0.3556 0.3556)
			(layers "F.Cu" "F.Mask" "F.Paste")
			(net "A_PVNN_STBY_PCH_SENSOR")
		)
		(pad "F4" smd circle
			(at -5.999988 -4.400042 90)
			(size 0.3556 0.3556)
			(layers "F.Cu" "F.Mask" "F.Paste")
			(net "A_P3V3_SCALED")
		)
		(pad "F5" smd circle
			(at -5.199888 -4.400042 90)
			(size 0.3556 0.3556)
			(layers "F.Cu" "F.Mask" "F.Paste")
			(net "A_P5V_SCALED")
		)
		(pad "F6" smd circle
			(at -4.400042 -4.400042 90)
			(size 0.3556 0.3556)
			(layers "F.Cu" "F.Mask" "F.Paste")
			(net "P1V15_AUX_BMC")
		)
		(pad "F7" smd circle
			(at -3.599942 -4.400042 90)
			(size 0.3556 0.3556)
			(layers "F.Cu" "F.Mask" "F.Paste")
			(net "P3V3_STBY")
		)
		(pad "F8" smd circle
			(at -2.800096 -4.400042 90)
			(size 0.3556 0.3556)
			(layers "F.Cu" "F.Mask" "F.Paste")
			(net "P3V3_STBY")
		)
		(pad "F9" smd circle
			(at -1.999996 -4.400042 90)
			(size 0.3556 0.3556)
			(layers "F.Cu" "F.Mask" "F.Paste")
			(net "RMII_BMC_OCP_TXD0_R")
		)
		(pad "F10" smd circle
			(at -1.199896 -4.400042 90)
			(size 0.3556 0.3556)
			(layers "F.Cu" "F.Mask" "F.Paste")
			(net "P3V3_STBY")
		)
		(pad "F11" smd circle
			(at -0.40005 -4.400042 90)
			(size 0.3556 0.3556)
			(layers "F.Cu" "F.Mask" "F.Paste")
			(net "P3V3_STBY")
		)
		(pad "F12" smd circle
			(at 0.40005 -4.400042 90)
			(size 0.3556 0.3556)
			(layers "F.Cu" "F.Mask" "F.Paste")
			(net "VCC_D_3V3")
		)
		(pad "F13" smd circle
			(at 1.199896 -4.400042 90)
			(size 0.3556 0.3556)
			(layers "F.Cu" "F.Mask" "F.Paste")
			(net "VCC_D_3V3")
		)
		(pad "F14" smd circle
			(at 1.999996 -4.400042 90)
			(size 0.3556 0.3556)
			(layers "F.Cu" "F.Mask" "F.Paste")
			(net "VCC_D_3V3")
		)
		(pad "F15" smd circle
			(at 2.800096 -4.400042 90)
			(size 0.3556 0.3556)
			(layers "F.Cu" "F.Mask" "F.Paste")
			(net "VCC_D_3V3")
		)
		(pad "F16" smd circle
			(at 3.599942 -4.400042 90)
			(size 0.3556 0.3556)
			(layers "F.Cu" "F.Mask" "F.Paste")
			(net "GND")
		)
		(pad "F17" smd circle
			(at 4.400042 -4.400042 90)
			(size 0.3556 0.3556)
			(layers "F.Cu" "F.Mask" "F.Paste")
			(net "FM_BMC_PWRBTN_OUT_N")
		)
		(pad "F18" smd circle
			(at 5.199888 -4.400042 90)
			(size 0.3556 0.3556)
			(layers "F.Cu" "F.Mask" "F.Paste")
			(net "FM_PWR_BTN_R1_N")
		)
		(pad "F19" smd circle
			(at 5.999988 -4.400042 90)
			(size 0.3556 0.3556)
			(layers "F.Cu" "F.Mask" "F.Paste")
			(net "FM_BIOS_MRC_DEBUG_MSG_DIS_N")
		)
		(pad "F20" smd circle
			(at 6.800088 -4.400042 90)
			(size 0.3556 0.3556)
			(layers "F.Cu" "F.Mask" "F.Paste")
			(net "FM_SOL_UART_CH_SEL")
		)
		(pad "F21" smd circle
			(at 7.599934 -4.400042 90)
			(size 0.3556 0.3556)
			(layers "F.Cu" "F.Mask" "F.Paste")
			(net "LPC_LFRAME_N_CS0_R_N")
		)
		(pad "F22" smd circle
			(at 8.400034 -4.400042 90)
			(size 0.3556 0.3556)
			(layers "F.Cu" "F.Mask" "F.Paste")
			(net "IRQ_LPC_SERIRQ_R")
		)
		(pad "G1" smd circle
			(at -8.400034 -3.599942 90)
			(size 0.3556 0.3556)
			(layers "F.Cu" "F.Mask" "F.Paste")
			(net "H_CPU0_MEMDEF_MEMHOT_LVT3_BMC_N")
		)
		(pad "G2" smd circle
			(at -7.599934 -3.599942 90)
			(size 0.3556 0.3556)
			(layers "F.Cu" "F.Mask" "F.Paste")
			(net "GND")
		)
		(pad "G3" smd circle
			(at -6.800088 -3.599942 90)
			(size 0.3556 0.3556)
			(layers "F.Cu" "F.Mask" "F.Paste")
			(net "GND")
		)
		(pad "G4" smd circle
			(at -5.999988 -3.599942 90)
			(size 0.3556 0.3556)
			(layers "F.Cu" "F.Mask" "F.Paste")
			(net "A_P3V_BAT_SCALED")
		)
		(pad "G5" smd circle
			(at -5.199888 -3.599942 90)
			(size 0.3556 0.3556)
			(layers "F.Cu" "F.Mask" "F.Paste")
			(net "A_P5V_STBY_SCALED")
		)
		(pad "G6" smd circle
			(at -4.400042 -3.599942 90)
			(size 0.3556 0.3556)
			(layers "F.Cu" "F.Mask" "F.Paste")
			(net "GND")
		)
		(pad "G7" smd circle
			(at -3.599942 -3.599942 90)
			(size 0.3556 0.3556)
			(layers "F.Cu" "F.Mask" "F.Paste")
			(net "P1V15_AUX_BMC")
		)
		(pad "G8" smd circle
			(at -2.800096 -3.599942 90)
			(size 0.3556 0.3556)
			(layers "F.Cu" "F.Mask" "F.Paste")
			(net "P1V15_AUX_BMC")
		)
		(pad "G9" smd circle
			(at -1.999996 -3.599942 90)
			(size 0.3556 0.3556)
			(layers "F.Cu" "F.Mask" "F.Paste")
			(net "P1V15_AUX_BMC")
		)
		(pad "G10" smd circle
			(at -1.199896 -3.599942 90)
			(size 0.3556 0.3556)
			(layers "F.Cu" "F.Mask" "F.Paste")
			(net "P1V15_AUX_BMC")
		)
		(pad "G11" smd circle
			(at -0.40005 -3.599942 90)
			(size 0.3556 0.3556)
			(layers "F.Cu" "F.Mask" "F.Paste")
			(net "P1V15_AUX_BMC")
		)
		(pad "G12" smd circle
			(at 0.40005 -3.599942 90)
			(size 0.3556 0.3556)
			(layers "F.Cu" "F.Mask" "F.Paste")
			(net "P1V15_AUX_BMC")
		)
		(pad "G13" smd circle
			(at 1.199896 -3.599942 90)
			(size 0.3556 0.3556)
			(layers "F.Cu" "F.Mask" "F.Paste")
			(net "P1V15_AUX_BMC")
		)
		(pad "G14" smd circle
			(at 1.999996 -3.599942 90)
			(size 0.3556 0.3556)
			(layers "F.Cu" "F.Mask" "F.Paste")
			(net "P1V15_AUX_BMC")
		)
		(pad "G15" smd circle
			(at 2.800096 -3.599942 90)
			(size 0.3556 0.3556)
			(layers "F.Cu" "F.Mask" "F.Paste")
			(net "P1V15_AUX_BMC")
		)
		(pad "G16" smd circle
			(at 3.599942 -3.599942 90)
			(size 0.3556 0.3556)
			(layers "F.Cu" "F.Mask" "F.Paste")
			(net "VCC_D_3V3")
		)
		(pad "G17" smd circle
			(at 4.400042 -3.599942 90)
			(size 0.3556 0.3556)
			(layers "F.Cu" "F.Mask" "F.Paste")
			(net "FM_BATTERY_SENSE_EN_N")
		)
		(pad "G18" smd circle
			(at 5.199888 -3.599942 90)
			(size 0.3556 0.3556)
			(layers "F.Cu" "F.Mask" "F.Paste")
			(net "FM_CPU_ERR0_LVT3_BMC_N")
		)
		(pad "G19" smd circle
			(at 5.999988 -3.599942 90)
			(size 0.3556 0.3556)
			(layers "F.Cu" "F.Mask" "F.Paste")
			(net "GND")
		)
		(pad "G20" smd circle
			(at 6.800088 -3.599942 90)
			(size 0.3556 0.3556)
			(layers "F.Cu" "F.Mask" "F.Paste")
			(net "LPC_LAD1_IO1_R")
		)
		(pad "G21" smd circle
			(at 7.599934 -3.599942 90)
			(size 0.3556 0.3556)
			(layers "F.Cu" "F.Mask" "F.Paste")
			(net "LPC_LAD0_IO0_R")
		)
		(pad "G22" smd circle
			(at 8.400034 -3.599942 90)
			(size 0.3556 0.3556)
			(layers "F.Cu" "F.Mask" "F.Paste")
			(net "RST_BMC_LVC3_N")
		)
		(pad "H1" smd circle
			(at -8.400034 -2.800096 90)
			(size 0.3556 0.3556)
			(layers "F.Cu" "F.Mask" "F.Paste")
			(net "P3V3_STBY_BMC_ADCVREFN")
		)
		(pad "H2" smd circle
			(at -7.599934 -2.800096 90)
			(size 0.3556 0.3556)
			(layers "F.Cu" "F.Mask" "F.Paste")
			(net "P3V3_STBY_BMC_ADCVREFP")
		)
		(pad "H3" smd circle
			(at -6.800088 -2.800096 90)
			(size 0.3556 0.3556)
			(layers "F.Cu" "F.Mask" "F.Paste")
			(net "H_CPU1_MEMGHJ_MEMHOT_LVT3_BMC_N")
		)
		(pad "H4" smd circle
			(at -5.999988 -2.800096 90)
			(size 0.3556 0.3556)
			(layers "F.Cu" "F.Mask" "F.Paste")
			(net "H_CPU1_MEMKLM_MEMHOT_LVT3_BMC_N")
		)
		(pad "H5" smd circle
			(at -5.199888 -2.800096 90)
			(size 0.3556 0.3556)
			(layers "F.Cu" "F.Mask" "F.Paste")
			(net "H_CPU0_MEMABC_MEMHOT_LVT3_BMC_N")
		)
		(pad "H6" smd circle
			(at -4.400042 -2.800096 90)
			(size 0.3556 0.3556)
			(layers "F.Cu" "F.Mask" "F.Paste")
			(net "GND")
		)
		(pad "H7" smd circle
			(at -3.599942 -2.800096 90)
			(size 0.3556 0.3556)
			(layers "F.Cu" "F.Mask" "F.Paste")
			(net "VCC_VA_3V3")
		)
		(pad "H16" smd circle
			(at 3.599942 -2.800096 90)
			(size 0.3556 0.3556)
			(layers "F.Cu" "F.Mask" "F.Paste")
			(net "P1V15_AUX_BMC")
		)
		(pad "H17" smd circle
			(at 4.400042 -2.800096 90)
			(size 0.3556 0.3556)
			(layers "F.Cu" "F.Mask" "F.Paste")
			(net "VCC_D_3V3")
		)
		(pad "H18" smd circle
			(at 5.199888 -2.800096 90)
			(size 0.3556 0.3556)
			(layers "F.Cu" "F.Mask" "F.Paste")
			(net "FM_OCP_MEZZC_PRES_LVT3_BMC")
		)
		(pad "H19" smd circle
			(at 5.999988 -2.800096 90)
			(size 0.3556 0.3556)
			(layers "F.Cu" "F.Mask" "F.Paste")
			(net "FM_OCP_MEZZB_PRES_LVT3_BMC")
		)
		(pad "H20" smd circle
			(at 6.800088 -2.800096 90)
			(size 0.3556 0.3556)
			(layers "F.Cu" "F.Mask" "F.Paste")
			(net "IRQ_PVDDQ_GHJ_VRHOT_LVT3_N")
		)
		(pad "H21" smd circle
			(at 7.599934 -2.800096 90)
			(size 0.3556 0.3556)
			(layers "F.Cu" "F.Mask" "F.Paste")
			(net "IRQ_BMC_PCH_SMI_LPC_N")
		)
	)
)
